#ISCELL
  mstr_misc dns *
  *
#ISCELL
  mstr_symbols design_note *
  *
#ISCELL
  mstr_symbols intel_corp_bpage *
  *
#ISCELL
  mstr_standard offpage *
  page210_i1
#CELL
  mstr_discrete inductor *
  page210_i10
#CELL
  mstr_discrete capp *
  page210_i12
#ISCELL
  mstr_symbols gnd *
  page210_i13
#CELL
  mstr_discrete capp *
  page210_i14
#ISCELL
  mstr_symbols gnd *
  page210_i15
#ISCELL
  mstr_standard offpage *
  page210_i17
#ISCELL
  mstr_standard offpage *
  page210_i18
#ISCELL
  mstr_standard offpage *
  page210_i2
#CELL
  mstr_discrete res *
  page210_i20
#ISCELL
  mstr_symbols vcc_core *
  page210_i21
#CELL
  mstr_discrete cap *
  page210_i22
#CELL
  dev_discrete cap_a *
  page210_i23
#CELL
  mstr_discrete cap *
  page210_i24
#CELL
  mstr_discrete cap *
  page210_i26
#CELL
  dev_discrete cap_a *
  page210_i27
#CELL
  mstr_discrete cap *
  page210_i28
#CELL
  mstr_discrete res *
  page210_i29
#ISCELL
  mstr_symbols gnd *
  page210_i30
#CELL
  mstr_discrete res *
  page210_i31
#CELL
  mstr_discrete res *
  page210_i32
#CELL
  mstr_discrete res *
  page210_i33
#CELL
  mstr_discrete res *
  page210_i34
#CELL
  mstr_discrete cap *
  page210_i35
#CELL
  mstr_discrete cap *
  page210_i36
#CELL
  mstr_discrete cap *
  page210_i38
#ISCELL
  mstr_symbols gnd *
  page210_i39
#ISCELL
  mstr_standard offpage *
  page210_i40
#ISCELL
  mstr_standard offpage *
  page210_i41
#ISCELL
  mstr_symbols p5v_stby *
  page210_i42
#CELL
  dev_discrete cap_a *
  page210_i44
#CELL
  mstr_discrete res *
  page210_i45
#ISCELL
  mstr_symbols pvsa_cpu1 *
  page210_i46
#ISCELL
  mstr_symbols pvsa_cpu1 *
  page210_i47
#ISCELL
  mstr_standard offpage *
  page210_i50
#CELL
  mstr_discrete ir354xx *
  page210_i51
#CELL
  mstr_discrete res *
  page210_i52
#ISCELL
  mstr_symbols gnd *
  page210_i53
#ISCELL
  mstr_symbols gnd *
  page210_i54
#CELL
  dev_discrete cap_a *
  page210_i55
#CELL
  w_hdl sc2k2p50v3kx-gp *
  page210_i57
#ISCELL
  mstr_symbols gnd *
  page210_i58
#CELL
  w_hdl 3d01r5f-gp *
  page210_i59
#ISCELL
  mstr_standard offpage *
  page210_i6
#CELL
  mstr_discrete cap *
  page210_i60
#ISCELL
  mstr_symbols gnd *
  page210_i61
#CELL
  mstr_discrete res *
  page210_i62
#ISCELL
  mstr_symbols pvsa_cpu1 *
  page210_i7
#CELL
  dev_discrete cap_a *
  page210_i8
#ISCELL
  mstr_symbols gnd *
  page210_i9
